(kicad_pcb
	(version 20260206)
	(generator "pcbnew")
	(generator_version "10.0")
	(general
		(thickness 1.6)
		(legacy_teardrops no)
	)
	(paper "A4")
	(title_block
		(title "01162023_DA0F0TEBIF0_F0T_Expander_BD_F_brd_V02_OCP.brd")
		(comment 1 "Grand Teton / footprints 9484-9492 of 9728")
	)
	(layers
		(0 "F.Cu" signal "TOP")
		(4 "In1.Cu" signal "GND")
		(6 "In2.Cu" signal "VCC")
		(8 "In3.Cu" signal "VCC1")
		(10 "In4.Cu" signal "GND1")
		(12 "In5.Cu" signal "IN1")
		(14 "In6.Cu" signal "GND2")
		(16 "In7.Cu" signal "IN2")
		(18 "In8.Cu" signal "GND3")
		(20 "In9.Cu" signal "IN3")
		(22 "In10.Cu" signal "GND4")
		(24 "In11.Cu" signal "IN4")
		(26 "In12.Cu" signal "GND5")
		(28 "In13.Cu" signal "IN5")
		(30 "In14.Cu" signal "GND6")
		(32 "In15.Cu" signal "IN6")
		(34 "In16.Cu" signal "GND7")
		(2 "B.Cu" signal "BOTTOM")
		(9 "F.Adhes" user "F.Adhesive")
		(11 "B.Adhes" user "B.Adhesive")
		(13 "F.Paste" user "Package Geometry/Pastemask Top")
		(15 "B.Paste" user "Package Geometry/Pastemask Bottom")
		(5 "F.SilkS" user "Ref Des/Silkscreen Top")
		(7 "B.SilkS" user "Ref Des/Silkscreen Bottom")
		(1 "F.Mask" user "Board Geometry/Soldermask Top")
		(3 "B.Mask" user "Board Geometry/Soldermask Bottom")
		(17 "Dwgs.User" user "User.Drawings")
		(19 "Cmts.User" user "User.Comments")
		(21 "Eco1.User" user "User.Eco1")
		(23 "Eco2.User" user "User.Eco2")
		(25 "Edge.Cuts" user "Board Geometry/Outline")
		(27 "Margin" user)
		(31 "F.CrtYd" user "Package Geometry/Place Bound Top")
		(29 "B.CrtYd" user "Package Geometry/Place Bound Bottom")
		(35 "F.Fab" user "Ref Des/Assembly Top")
		(33 "B.Fab" user "Ref Des/Assembly Bottom")
	)
	(footprint ""
		(layer "B.Cu")
		(at 65.824862 -286.399732 90)
		(property "Reference" "C2979"
			(at 0 0 90)
			(layer "B.SilkS")
			(hide yes)
			(effects
				(font
					(size 1.27 1.27)
				)
				(justify mirror)
			)
		)
		(property "Value" ""
			(at 0 0 90)
			(layer "B.Fab")
			(effects
				(font
					(size 1.27 1.27)
				)
				(justify mirror)
			)
		)
		(duplicate_pad_numbers_are_jumpers no)
		(fp_line
			(start 0.299974 -0.150114)
			(end -0.299974 -0.150114)
			(stroke
				(width 0.1)
				(type default)
			)
			(layer "B.Fab")
		)
		(fp_line
			(start -0.299974 -0.150114)
			(end -0.299974 0.150114)
			(stroke
				(width 0.1)
				(type default)
			)
			(layer "B.Fab")
		)
		(fp_line
			(start 0.299974 0.150114)
			(end 0.299974 -0.150114)
			(stroke
				(width 0.1)
				(type default)
			)
			(layer "B.Fab")
		)
		(fp_line
			(start -0.299974 0.150114)
			(end 0.299974 0.150114)
			(stroke
				(width 0.1)
				(type default)
			)
			(layer "B.Fab")
		)
		(pad "1" smd rect
			(at 0.2667 0 270)
			(size 0.3048 0.381)
			(layers "B.Cu" "B.Mask" "B.Paste")
			(net "P1V25_SERDES_VDDPLL_PEX0")
		)
		(pad "2" smd rect
			(at -0.2667 0 270)
			(size 0.3048 0.381)
			(layers "B.Cu" "B.Mask" "B.Paste")
			(net "GND")
		)
	)
	(footprint ""
		(layer "B.Cu")
		(at 236.18952 -285.911544)
		(property "Reference" "PC255"
			(at 0 0 0)
			(layer "B.SilkS")
			(hide yes)
			(effects
				(font
					(size 1.27 1.27)
				)
				(justify mirror)
			)
		)
		(property "Value" ""
			(at 0 0 0)
			(layer "B.Fab")
			(effects
				(font
					(size 1.27 1.27)
				)
				(justify mirror)
			)
		)
		(duplicate_pad_numbers_are_jumpers no)
		(fp_line
			(start -1.524 -0.762)
			(end -1.524 0.762)
			(stroke
				(width 0.1524)
				(type default)
			)
			(layer "B.SilkS")
		)
		(fp_line
			(start -1.524 0.762)
			(end 1.524 0.762)
			(stroke
				(width 0.1524)
				(type default)
			)
			(layer "B.SilkS")
		)
		(fp_line
			(start 1.524 -0.762)
			(end -1.524 -0.762)
			(stroke
				(width 0.1524)
				(type default)
			)
			(layer "B.SilkS")
		)
		(fp_line
			(start 1.524 0.762)
			(end 1.524 -0.762)
			(stroke
				(width 0.1524)
				(type default)
			)
			(layer "B.SilkS")
		)
		(fp_line
			(start -1.1049 -0.724916)
			(end 1.1049 -0.724916)
			(stroke
				(width 0.1)
				(type default)
			)
			(layer "B.Fab")
		)
		(fp_line
			(start -1.1049 0.724916)
			(end -1.1049 -0.724916)
			(stroke
				(width 0.1)
				(type default)
			)
			(layer "B.Fab")
		)
		(fp_line
			(start 1.1049 -0.724916)
			(end 1.1049 0.724916)
			(stroke
				(width 0.1)
				(type default)
			)
			(layer "B.Fab")
		)
		(fp_line
			(start 1.1049 0.724916)
			(end -1.1049 0.724916)
			(stroke
				(width 0.1)
				(type default)
			)
			(layer "B.Fab")
		)
		(pad "1" smd rect
			(at 0.889 0)
			(size 1.016 1.27)
			(layers "B.Cu" "B.Mask" "B.Paste")
			(net "P1V25_PEX2_R")
		)
		(pad "2" smd rect
			(at -0.889 0)
			(size 1.016 1.27)
			(layers "B.Cu" "B.Mask" "B.Paste")
			(net "GND")
		)
	)
	(footprint ""
		(layer "B.Cu")
		(at 409.897326 -109.481366)
		(property "Reference" "R388"
			(at 0 0 0)
			(layer "B.SilkS")
			(hide yes)
			(effects
				(font
					(size 1.27 1.27)
				)
				(justify mirror)
			)
		)
		(property "Value" ""
			(at 0 0 0)
			(layer "B.Fab")
			(effects
				(font
					(size 1.27 1.27)
				)
				(justify mirror)
			)
		)
		(duplicate_pad_numbers_are_jumpers no)
		(fp_line
			(start -0.7874 -0.4064)
			(end -0.7874 0.4064)
			(stroke
				(width 0.1524)
				(type default)
			)
			(layer "B.SilkS")
		)
		(fp_line
			(start -0.7874 0.4064)
			(end 0.7874 0.4064)
			(stroke
				(width 0.1524)
				(type default)
			)
			(layer "B.SilkS")
		)
		(fp_line
			(start 0.7874 -0.4064)
			(end -0.7874 -0.4064)
			(stroke
				(width 0.1524)
				(type default)
			)
			(layer "B.SilkS")
		)
		(fp_line
			(start 0.7874 0.4064)
			(end 0.7874 -0.4064)
			(stroke
				(width 0.1524)
				(type default)
			)
			(layer "B.SilkS")
		)
		(fp_line
			(start -0.67945 -0.3048)
			(end -0.67945 0.3048)
			(stroke
				(width 0.1)
				(type default)
			)
			(layer "B.Fab")
		)
		(fp_line
			(start -0.67945 0.3048)
			(end -0.120396 0.3048)
			(stroke
				(width 0.1)
				(type default)
			)
			(layer "B.Fab")
		)
		(fp_line
			(start -0.12065 -0.3048)
			(end -0.67945 -0.3048)
			(stroke
				(width 0.1)
				(type default)
			)
			(layer "B.Fab")
		)
		(fp_line
			(start -0.12065 -0.2794)
			(end -0.12065 -0.3048)
			(stroke
				(width 0.1)
				(type default)
			)
			(layer "B.Fab")
		)
		(fp_line
			(start -0.120396 0.2794)
			(end 0.12065 0.2794)
			(stroke
				(width 0.1)
				(type default)
			)
			(layer "B.Fab")
		)
		(fp_line
			(start -0.120396 0.3048)
			(end -0.120396 0.2794)
			(stroke
				(width 0.1)
				(type default)
			)
			(layer "B.Fab")
		)
		(fp_line
			(start 0.12065 -0.305054)
			(end 0.12065 -0.2794)
			(stroke
				(width 0.1)
				(type default)
			)
			(layer "B.Fab")
		)
		(fp_line
			(start 0.12065 -0.2794)
			(end -0.12065 -0.2794)
			(stroke
				(width 0.1)
				(type default)
			)
			(layer "B.Fab")
		)
		(fp_line
			(start 0.12065 0.2794)
			(end 0.12065 0.3048)
			(stroke
				(width 0.1)
				(type default)
			)
			(layer "B.Fab")
		)
		(fp_line
			(start 0.12065 0.3048)
			(end 0.67945 0.3048)
			(stroke
				(width 0.1)
				(type default)
			)
			(layer "B.Fab")
		)
		(fp_line
			(start 0.67945 -0.305054)
			(end 0.12065 -0.305054)
			(stroke
				(width 0.1)
				(type default)
			)
			(layer "B.Fab")
		)
		(fp_line
			(start 0.67945 0.3048)
			(end 0.67945 -0.305054)
			(stroke
				(width 0.1)
				(type default)
			)
			(layer "B.Fab")
		)
		(pad "1" smd circle
			(at 0.40005 0 180)
			(size 0 0)
			(layers "B.Cu" "B.Mask" "B.Paste")
			(net "NIC7_BIF1_N")
		)
		(pad "2" smd circle
			(at -0.40005 0 180)
			(size 0 0)
			(layers "B.Cu" "B.Mask" "B.Paste")
			(net "P3V3_AUX")
		)
	)
	(footprint ""
		(layer "B.Cu")
		(at 207.110076 -220.746066)
		(property "Reference" "R6819"
			(at 0 0 0)
			(layer "B.SilkS")
			(hide yes)
			(effects
				(font
					(size 1.27 1.27)
				)
				(justify mirror)
			)
		)
		(property "Value" ""
			(at 0 0 0)
			(layer "B.Fab")
			(effects
				(font
					(size 1.27 1.27)
				)
				(justify mirror)
			)
		)
		(duplicate_pad_numbers_are_jumpers no)
		(fp_line
			(start -0.7874 -0.4064)
			(end -0.7874 0.4064)
			(stroke
				(width 0.1524)
				(type default)
			)
			(layer "B.SilkS")
		)
		(fp_line
			(start -0.7874 0.4064)
			(end 0.7874 0.4064)
			(stroke
				(width 0.1524)
				(type default)
			)
			(layer "B.SilkS")
		)
		(fp_line
			(start 0.7874 -0.4064)
			(end -0.7874 -0.4064)
			(stroke
				(width 0.1524)
				(type default)
			)
			(layer "B.SilkS")
		)
		(fp_line
			(start 0.7874 0.4064)
			(end 0.7874 -0.4064)
			(stroke
				(width 0.1524)
				(type default)
			)
			(layer "B.SilkS")
		)
		(fp_line
			(start -0.67945 -0.3048)
			(end -0.67945 0.3048)
			(stroke
				(width 0.1)
				(type default)
			)
			(layer "B.Fab")
		)
		(fp_line
			(start -0.67945 0.3048)
			(end -0.120396 0.3048)
			(stroke
				(width 0.1)
				(type default)
			)
			(layer "B.Fab")
		)
		(fp_line
			(start -0.12065 -0.3048)
			(end -0.67945 -0.3048)
			(stroke
				(width 0.1)
				(type default)
			)
			(layer "B.Fab")
		)
		(fp_line
			(start -0.12065 -0.2794)
			(end -0.12065 -0.3048)
			(stroke
				(width 0.1)
				(type default)
			)
			(layer "B.Fab")
		)
		(fp_line
			(start -0.120396 0.2794)
			(end 0.12065 0.2794)
			(stroke
				(width 0.1)
				(type default)
			)
			(layer "B.Fab")
		)
		(fp_line
			(start -0.120396 0.3048)
			(end -0.120396 0.2794)
			(stroke
				(width 0.1)
				(type default)
			)
			(layer "B.Fab")
		)
		(fp_line
			(start 0.12065 -0.305054)
			(end 0.12065 -0.2794)
			(stroke
				(width 0.1)
				(type default)
			)
			(layer "B.Fab")
		)
		(fp_line
			(start 0.12065 -0.2794)
			(end -0.12065 -0.2794)
			(stroke
				(width 0.1)
				(type default)
			)
			(layer "B.Fab")
		)
		(fp_line
			(start 0.12065 0.2794)
			(end 0.12065 0.3048)
			(stroke
				(width 0.1)
				(type default)
			)
			(layer "B.Fab")
		)
		(fp_line
			(start 0.12065 0.3048)
			(end 0.67945 0.3048)
			(stroke
				(width 0.1)
				(type default)
			)
			(layer "B.Fab")
		)
		(fp_line
			(start 0.67945 -0.305054)
			(end 0.12065 -0.305054)
			(stroke
				(width 0.1)
				(type default)
			)
			(layer "B.Fab")
		)
		(fp_line
			(start 0.67945 0.3048)
			(end 0.67945 -0.305054)
			(stroke
				(width 0.1)
				(type default)
			)
			(layer "B.Fab")
		)
		(pad "1" smd circle
			(at 0.40005 0 180)
			(size 0 0)
			(layers "B.Cu" "B.Mask" "B.Paste")
			(net "GND")
		)
		(pad "2" smd circle
			(at -0.40005 0 180)
			(size 0 0)
			(layers "B.Cu" "B.Mask" "B.Paste")
			(net "BOARD_TYPE_1_ADC_R")
		)
	)
	(footprint ""
		(layer "B.Cu")
		(at 352.11893 -233.553 90)
		(property "Reference" "R5777"
			(at 0 0 90)
			(layer "B.SilkS")
			(hide yes)
			(effects
				(font
					(size 1.27 1.27)
				)
				(justify mirror)
			)
		)
		(property "Value" ""
			(at 0 0 90)
			(layer "B.Fab")
			(effects
				(font
					(size 1.27 1.27)
				)
				(justify mirror)
			)
		)
		(duplicate_pad_numbers_are_jumpers no)
		(fp_line
			(start 0.7874 -0.4064)
			(end -0.7874 -0.4064)
			(stroke
				(width 0.1524)
				(type default)
			)
			(layer "B.SilkS")
		)
		(fp_line
			(start -0.7874 -0.4064)
			(end -0.7874 0.4064)
			(stroke
				(width 0.1524)
				(type default)
			)
			(layer "B.SilkS")
		)
		(fp_line
			(start 0.7874 0.4064)
			(end 0.7874 -0.4064)
			(stroke
				(width 0.1524)
				(type default)
			)
			(layer "B.SilkS")
		)
		(fp_line
			(start -0.7874 0.4064)
			(end 0.7874 0.4064)
			(stroke
				(width 0.1524)
				(type default)
			)
			(layer "B.SilkS")
		)
		(fp_line
			(start 0.67945 -0.305054)
			(end 0.12065 -0.305054)
			(stroke
				(width 0.1)
				(type default)
			)
			(layer "B.Fab")
		)
		(fp_line
			(start 0.12065 -0.305054)
			(end 0.12065 -0.2794)
			(stroke
				(width 0.1)
				(type default)
			)
			(layer "B.Fab")
		)
		(fp_line
			(start -0.12065 -0.3048)
			(end -0.67945 -0.3048)
			(stroke
				(width 0.1)
				(type default)
			)
			(layer "B.Fab")
		)
		(fp_line
			(start -0.67945 -0.3048)
			(end -0.67945 0.3048)
			(stroke
				(width 0.1)
				(type default)
			)
			(layer "B.Fab")
		)
		(fp_line
			(start 0.12065 -0.2794)
			(end -0.12065 -0.2794)
			(stroke
				(width 0.1)
				(type default)
			)
			(layer "B.Fab")
		)
		(fp_line
			(start -0.12065 -0.2794)
			(end -0.12065 -0.3048)
			(stroke
				(width 0.1)
				(type default)
			)
			(layer "B.Fab")
		)
		(fp_line
			(start 0.12065 0.2794)
			(end 0.12065 0.3048)
			(stroke
				(width 0.1)
				(type default)
			)
			(layer "B.Fab")
		)
		(fp_line
			(start -0.120396 0.2794)
			(end 0.12065 0.2794)
			(stroke
				(width 0.1)
				(type default)
			)
			(layer "B.Fab")
		)
		(fp_line
			(start 0.67945 0.3048)
			(end 0.67945 -0.305054)
			(stroke
				(width 0.1)
				(type default)
			)
			(layer "B.Fab")
		)
		(fp_line
			(start 0.12065 0.3048)
			(end 0.67945 0.3048)
			(stroke
				(width 0.1)
				(type default)
			)
			(layer "B.Fab")
		)
		(fp_line
			(start -0.120396 0.3048)
			(end -0.120396 0.2794)
			(stroke
				(width 0.1)
				(type default)
			)
			(layer "B.Fab")
		)
		(fp_line
			(start -0.67945 0.3048)
			(end -0.120396 0.3048)
			(stroke
				(width 0.1)
				(type default)
			)
			(layer "B.Fab")
		)
		(pad "1" smd circle
			(at 0.40005 0 270)
			(size 0 0)
			(layers "B.Cu" "B.Mask" "B.Paste")
			(net "P3V3_AUX")
		)
		(pad "2" smd circle
			(at -0.40005 0 270)
			(size 0 0)
			(layers "B.Cu" "B.Mask" "B.Paste")
			(net "PU_FPGA_PROGRAMN")
		)
	)
	(footprint ""
		(layer "B.Cu")
		(at 289.94989 -299.699934 -90)
		(property "Reference" "C1747"
			(at 0 0 90)
			(layer "B.SilkS")
			(hide yes)
			(effects
				(font
					(size 1.27 1.27)
				)
				(justify mirror)
			)
		)
		(property "Value" ""
			(at 0 0 90)
			(layer "B.Fab")
			(effects
				(font
					(size 1.27 1.27)
				)
				(justify mirror)
			)
		)
		(duplicate_pad_numbers_are_jumpers no)
		(fp_line
			(start -0.299974 0.150114)
			(end 0.299974 0.150114)
			(stroke
				(width 0.1)
				(type default)
			)
			(layer "B.Fab")
		)
		(fp_line
			(start 0.299974 0.150114)
			(end 0.299974 -0.150114)
			(stroke
				(width 0.1)
				(type default)
			)
			(layer "B.Fab")
		)
		(fp_line
			(start -0.299974 -0.150114)
			(end -0.299974 0.150114)
			(stroke
				(width 0.1)
				(type default)
			)
			(layer "B.Fab")
		)
		(fp_line
			(start 0.299974 -0.150114)
			(end -0.299974 -0.150114)
			(stroke
				(width 0.1)
				(type default)
			)
			(layer "B.Fab")
		)
		(pad "1" smd rect
			(at 0.2667 0 90)
			(size 0.3048 0.381)
			(layers "B.Cu" "B.Mask" "B.Paste")
			(net "P0V8_SERDES_VDDA_PEX2")
		)
		(pad "2" smd rect
			(at -0.2667 0 90)
			(size 0.3048 0.381)
			(layers "B.Cu" "B.Mask" "B.Paste")
			(net "GND")
		)
	)
	(footprint ""
		(layer "B.Cu")
		(at 229.150418 -226.68357)
		(property "Reference" "C4487"
			(at 0 0 0)
			(layer "B.SilkS")
			(hide yes)
			(effects
				(font
					(size 1.27 1.27)
				)
				(justify mirror)
			)
		)
		(property "Value" ""
			(at 0 0 0)
			(layer "B.Fab")
			(effects
				(font
					(size 1.27 1.27)
				)
				(justify mirror)
			)
		)
		(duplicate_pad_numbers_are_jumpers no)
		(fp_line
			(start -0.7874 -0.4064)
			(end -0.7874 0.4064)
			(stroke
				(width 0.1524)
				(type default)
			)
			(layer "B.SilkS")
		)
		(fp_line
			(start -0.7874 0.4064)
			(end 0.7874 0.4064)
			(stroke
				(width 0.1524)
				(type default)
			)
			(layer "B.SilkS")
		)
		(fp_line
			(start 0.7874 -0.4064)
			(end -0.7874 -0.4064)
			(stroke
				(width 0.1524)
				(type default)
			)
			(layer "B.SilkS")
		)
		(fp_line
			(start 0.7874 0.4064)
			(end 0.7874 -0.4064)
			(stroke
				(width 0.1524)
				(type default)
			)
			(layer "B.SilkS")
		)
		(fp_line
			(start -0.67945 -0.3048)
			(end -0.67945 0.3048)
			(stroke
				(width 0.1)
				(type default)
			)
			(layer "B.Fab")
		)
		(fp_line
			(start -0.67945 0.3048)
			(end -0.120396 0.3048)
			(stroke
				(width 0.1)
				(type default)
			)
			(layer "B.Fab")
		)
		(fp_line
			(start -0.12065 -0.3048)
			(end -0.67945 -0.3048)
			(stroke
				(width 0.1)
				(type default)
			)
			(layer "B.Fab")
		)
		(fp_line
			(start -0.12065 -0.2794)
			(end -0.12065 -0.3048)
			(stroke
				(width 0.1)
				(type default)
			)
			(layer "B.Fab")
		)
		(fp_line
			(start -0.120396 0.2794)
			(end 0.12065 0.2794)
			(stroke
				(width 0.1)
				(type default)
			)
			(layer "B.Fab")
		)
		(fp_line
			(start -0.120396 0.3048)
			(end -0.120396 0.2794)
			(stroke
				(width 0.1)
				(type default)
			)
			(layer "B.Fab")
		)
		(fp_line
			(start 0.12065 -0.305054)
			(end 0.12065 -0.2794)
			(stroke
				(width 0.1)
				(type default)
			)
			(layer "B.Fab")
		)
		(fp_line
			(start 0.12065 -0.2794)
			(end -0.12065 -0.2794)
			(stroke
				(width 0.1)
				(type default)
			)
			(layer "B.Fab")
		)
		(fp_line
			(start 0.12065 0.2794)
			(end 0.12065 0.3048)
			(stroke
				(width 0.1)
				(type default)
			)
			(layer "B.Fab")
		)
		(fp_line
			(start 0.12065 0.3048)
			(end 0.67945 0.3048)
			(stroke
				(width 0.1)
				(type default)
			)
			(layer "B.Fab")
		)
		(fp_line
			(start 0.67945 -0.305054)
			(end 0.12065 -0.305054)
			(stroke
				(width 0.1)
				(type default)
			)
			(layer "B.Fab")
		)
		(fp_line
			(start 0.67945 0.3048)
			(end 0.67945 -0.305054)
			(stroke
				(width 0.1)
				(type default)
			)
			(layer "B.Fab")
		)
		(pad "1" smd circle
			(at 0.40005 0 180)
			(size 0 0)
			(layers "B.Cu" "B.Mask" "B.Paste")
			(net "BOARD_TYPE_0_ADC_R")
		)
		(pad "2" smd circle
			(at -0.40005 0 180)
			(size 0 0)
			(layers "B.Cu" "B.Mask" "B.Paste")
			(net "GND")
		)
	)
	(footprint ""
		(layer "B.Cu")
		(at 131.996942 -308.668674 90)
		(property "Reference" "C4265"
			(at 0 0 90)
			(layer "B.SilkS")
			(hide yes)
			(effects
				(font
					(size 1.27 1.27)
				)
				(justify mirror)
			)
		)
		(property "Value" ""
			(at 0 0 90)
			(layer "B.Fab")
			(effects
				(font
					(size 1.27 1.27)
				)
				(justify mirror)
			)
		)
		(duplicate_pad_numbers_are_jumpers no)
		(fp_line
			(start 0.299974 -0.150114)
			(end -0.299974 -0.150114)
			(stroke
				(width 0.1)
				(type default)
			)
			(layer "B.Fab")
		)
		(fp_line
			(start -0.299974 -0.150114)
			(end -0.299974 0.150114)
			(stroke
				(width 0.1)
				(type default)
			)
			(layer "B.Fab")
		)
		(fp_line
			(start 0.299974 0.150114)
			(end 0.299974 -0.150114)
			(stroke
				(width 0.1)
				(type default)
			)
			(layer "B.Fab")
		)
		(fp_line
			(start -0.299974 0.150114)
			(end 0.299974 0.150114)
			(stroke
				(width 0.1)
				(type default)
			)
			(layer "B.Fab")
		)
		(pad "1" smd rect
			(at 0.2667 0 270)
			(size 0.3048 0.381)
			(layers "B.Cu" "B.Mask" "B.Paste")
			(net "P0V8_PEX1")
		)
		(pad "2" smd rect
			(at -0.2667 0 270)
			(size 0.3048 0.381)
			(layers "B.Cu" "B.Mask" "B.Paste")
			(net "GND")
		)
	)
	(footprint ""
		(layer "B.Cu")
		(at 299.924724 -286.399732 90)
		(property "Reference" "C3299"
			(at 0 0 90)
			(layer "B.SilkS")
			(hide yes)
			(effects
				(font
					(size 1.27 1.27)
				)
				(justify mirror)
			)
		)
		(property "Value" ""
			(at 0 0 90)
			(layer "B.Fab")
			(effects
				(font
					(size 1.27 1.27)
				)
				(justify mirror)
			)
		)
		(duplicate_pad_numbers_are_jumpers no)
		(fp_line
			(start 0.299974 -0.150114)
			(end -0.299974 -0.150114)
			(stroke
				(width 0.1)
				(type default)
			)
			(layer "B.Fab")
		)
		(fp_line
			(start -0.299974 -0.150114)
			(end -0.299974 0.150114)
			(stroke
				(width 0.1)
				(type default)
			)
			(layer "B.Fab")
		)
		(fp_line
			(start 0.299974 0.150114)
			(end 0.299974 -0.150114)
			(stroke
				(width 0.1)
				(type default)
			)
			(layer "B.Fab")
		)
		(fp_line
			(start -0.299974 0.150114)
			(end 0.299974 0.150114)
			(stroke
				(width 0.1)
				(type default)
			)
			(layer "B.Fab")
		)
		(pad "1" smd rect
			(at 0.2667 0 270)
			(size 0.3048 0.381)
			(layers "B.Cu" "B.Mask" "B.Paste")
			(net "P1V25_SERDES_VDDPLL_PEX2")
		)
		(pad "2" smd rect
			(at -0.2667 0 270)
			(size 0.3048 0.381)
			(layers "B.Cu" "B.Mask" "B.Paste")
			(net "GND")
		)
	)
)
